# BASEBOARD_FAB2 (Tioga Pass) — schematic netlist excerpt (pin names and nets, part order shuffled) for the footprints in the layout excerpt that follows; sources: Cadence DE-HDL packaged netlist, KiCad conversion of Wiwynn_Tioga_Pass_MB.brd

R8E37  RES  0.0 5% CHIP  pkg 0402  page 241 : A = VR_P5V_STBY_VSENSE_R ; B = P5V_STBY
R2P1  RES  0.0 5% CHIP  pkg 0402  page 121 : A = RMII_SPRNGVLLE_BMC_PCH_RXD1 ; B = RMII_SPRNGVLLE_BMC_PCH_RXD1_R1
C1W7  CAP  10UF 6.3V 20% X6S  pkg 0603  page 239 : A = P3V3_STBY ; B = GND

(kicad_pcb
	(version 20260206)
	(generator "pcbnew")
	(generator_version "10.0")
	(general
		(thickness 1.6)
		(legacy_teardrops no)
	)
	(paper "A4")
	(title_block
		(title "Wiwynn_Tioga_Pass_MB.brd")
		(comment 1 "Tioga Pass / footprints 331-333 of 4770")
	)
	(layers
		(0 "F.Cu" signal "TOP")
		(4 "In1.Cu" signal "L2GND")
		(6 "In2.Cu" signal "L3")
		(8 "In3.Cu" signal "L4GND")
		(10 "In4.Cu" signal "L5")
		(12 "In5.Cu" signal "L6GND")
		(14 "In6.Cu" signal "L7VCC")
		(16 "In7.Cu" signal "L8VCC")
		(18 "In8.Cu" signal "L9GND")
		(20 "In9.Cu" signal "L10")
		(22 "In10.Cu" signal "L11GND")
		(24 "In11.Cu" signal "L12")
		(26 "In12.Cu" signal "L13GND")
		(2 "B.Cu" signal "BOTTOM")
		(9 "F.Adhes" user "F.Adhesive")
		(11 "B.Adhes" user "B.Adhesive")
		(13 "F.Paste" user "Package Geometry/Pastemask Top")
		(15 "B.Paste" user "Package Geometry/Pastemask Bottom")
		(5 "F.SilkS" user "Ref Des/Silkscreen Top")
		(7 "B.SilkS" user "Ref Des/Silkscreen Bottom")
		(1 "F.Mask" user "Board Geometry/Soldermask Top")
		(3 "B.Mask" user "Board Geometry/Soldermask Bottom")
		(17 "Dwgs.User" user "User.Drawings")
		(19 "Cmts.User" user "User.Comments")
		(21 "Eco1.User" user "User.Eco1")
		(23 "Eco2.User" user "User.Eco2")
		(25 "Edge.Cuts" user "Board Geometry/Outline")
		(27 "Margin" user)
		(31 "F.CrtYd" user "Package Geometry/Place Bound Top")
		(29 "B.CrtYd" user "Package Geometry/Place Bound Bottom")
		(35 "F.Fab" user "Ref Des/Assembly Top")
		(33 "B.Fab" user "Ref Des/Assembly Bottom")
	)
	(footprint ""
		(layer "F.Cu")
		(at 393.916408 -61.773308 180)
		(property "Reference" "R8E37"
			(at 0 0 180)
			(layer "F.SilkS")
			(hide yes)
			(effects
				(font
					(size 1.27 1.27)
				)
			)
		)
		(property "Value" ""
			(at 0 0 180)
			(layer "F.Fab")
			(effects
				(font
					(size 1.27 1.27)
				)
			)
		)
		(duplicate_pad_numbers_are_jumpers no)
		(fp_poly
			(pts
				(xy -0.2794 -0.1016) (xy 0.2794 -0.1016) (xy 0.2794 0.9906) (xy -0.2794 0.9906)
			)
			(stroke
				(width 0)
				(type default)
			)
			(fill no)
			(layer "F.CrtYd")
		)
		(fp_line
			(start 0.2794 0.9906)
			(end 0.2794 -0.1016)
			(stroke
				(width 0.1)
				(type default)
			)
			(layer "F.Fab")
		)
		(fp_line
			(start 0.2794 -0.1016)
			(end -0.2794 -0.1016)
			(stroke
				(width 0.1)
				(type default)
			)
			(layer "F.Fab")
		)
		(fp_line
			(start -0.2794 0.9906)
			(end 0.2794 0.9906)
			(stroke
				(width 0.1)
				(type default)
			)
			(layer "F.Fab")
		)
		(fp_line
			(start -0.2794 -0.1016)
			(end -0.2794 0.9906)
			(stroke
				(width 0.1)
				(type default)
			)
			(layer "F.Fab")
		)
		(pad "1" smd rect
			(at 0 0 180)
			(size 0.508 0.508)
			(layers "F.Cu" "F.Mask" "F.Paste")
			(net "VR_P5V_STBY_VSENSE_R")
		)
		(pad "2" smd rect
			(at 0 0.889 180)
			(size 0.508 0.508)
			(layers "F.Cu" "F.Mask" "F.Paste")
			(net "P5V_STBY")
		)
		(zone
			(layer "F.Cu")
			(hatch none 0.5)
			(connect_pads
				(clearance 0)
			)
			(min_thickness 0.25)
			(keepout
				(tracks not_allowed)
				(vias allowed)
				(pads allowed)
				(copperpour not_allowed)
				(footprints allowed)
			)
			(placement
				(enabled no)
				(sheetname "")
			)
			(fill
				(thermal_gap 0.5)
				(thermal_bridge_width 0.5)
				(island_removal_mode 0)
			)
			(polygon
				(pts
					(xy 394.170408 -62.408308) (xy 393.662408 -62.408308) (xy 393.662408 -62.027308) (xy 394.170408 -62.027308)
				)
			)
		)
		(zone
			(layer "F.Cu")
			(hatch none 0.5)
			(connect_pads
				(clearance 0)
			)
			(min_thickness 0.25)
			(keepout
				(tracks allowed)
				(vias not_allowed)
				(pads allowed)
				(copperpour not_allowed)
				(footprints allowed)
			)
			(placement
				(enabled no)
				(sheetname "")
			)
			(fill
				(thermal_gap 0.5)
				(thermal_bridge_width 0.5)
				(island_removal_mode 0)
			)
			(polygon
				(pts
					(xy 394.170408 -62.027308) (xy 393.662408 -62.027308) (xy 393.662408 -62.408308) (xy 394.170408 -62.408308)
				)
			)
		)
	)
	(footprint ""
		(layer "F.Cu")
		(at 456.5015 -24.8412 -90)
		(property "Reference" "C1W7"
			(at 0.97536 0.76708 180)
			(unlocked yes)
			(layer "F.SilkS")
			(effects
				(font
					(size 0.4064 0.254)
					(thickness 0.1524)
				)
			)
		)
		(property "Value" ""
			(at 0 0 270)
			(layer "F.Fab")
			(effects
				(font
					(size 1.27 1.27)
				)
			)
		)
		(duplicate_pad_numbers_are_jumpers no)
		(fp_poly
			(pts
				(xy -0.4953 -0.2032) (xy 0.4953 -0.2032) (xy 0.4953 1.6002) (xy -0.4953 1.6002)
			)
			(stroke
				(width 0)
				(type default)
			)
			(fill no)
			(layer "F.CrtYd")
		)
		(fp_line
			(start -0.4953 1.6002)
			(end -0.4953 -0.2032)
			(stroke
				(width 0.1)
				(type default)
			)
			(layer "F.Fab")
		)
		(fp_line
			(start 0.4953 1.6002)
			(end -0.4953 1.6002)
			(stroke
				(width 0.1)
				(type default)
			)
			(layer "F.Fab")
		)
		(fp_line
			(start -0.4953 -0.2032)
			(end 0.4953 -0.2032)
			(stroke
				(width 0.1)
				(type default)
			)
			(layer "F.Fab")
		)
		(fp_line
			(start 0.4953 -0.2032)
			(end 0.4953 1.6002)
			(stroke
				(width 0.1)
				(type default)
			)
			(layer "F.Fab")
		)
		(pad "1" smd rect
			(at 0 0 270)
			(size 0.762 0.889)
			(layers "F.Cu" "F.Mask" "F.Paste")
			(net "P3V3_STBY")
		)
		(pad "2" smd rect
			(at 0 1.397 270)
			(size 0.762 0.889)
			(layers "F.Cu" "F.Mask" "F.Paste")
			(net "GND")
		)
		(zone
			(layer "F.Cu")
			(hatch none 0.5)
			(connect_pads
				(clearance 0)
			)
			(min_thickness 0.25)
			(keepout
				(tracks not_allowed)
				(vias allowed)
				(pads allowed)
				(copperpour not_allowed)
				(footprints allowed)
			)
			(placement
				(enabled no)
				(sheetname "")
			)
			(fill
				(thermal_gap 0.5)
				(thermal_bridge_width 0.5)
				(island_removal_mode 0)
			)
			(polygon
				(pts
					(xy 456.057 -25.2222) (xy 456.057 -24.4602) (xy 455.549 -24.4602) (xy 455.549 -25.2222)
				)
			)
		)
	)
	(footprint ""
		(layer "F.Cu")
		(at 390.652 -87.3125 180)
		(property "Reference" "R2P1"
			(at 0 0 180)
			(layer "F.SilkS")
			(hide yes)
			(effects
				(font
					(size 1.27 1.27)
				)
			)
		)
		(property "Value" ""
			(at 0 0 180)
			(layer "F.Fab")
			(effects
				(font
					(size 1.27 1.27)
				)
			)
		)
		(duplicate_pad_numbers_are_jumpers no)
		(fp_poly
			(pts
				(xy -0.2794 -0.1016) (xy 0.2794 -0.1016) (xy 0.2794 0.9906) (xy -0.2794 0.9906)
			)
			(stroke
				(width 0)
				(type default)
			)
			(fill no)
			(layer "F.CrtYd")
		)
		(fp_line
			(start 0.2794 0.9906)
			(end 0.2794 -0.1016)
			(stroke
				(width 0.1)
				(type default)
			)
			(layer "F.Fab")
		)
		(fp_line
			(start 0.2794 -0.1016)
			(end -0.2794 -0.1016)
			(stroke
				(width 0.1)
				(type default)
			)
			(layer "F.Fab")
		)
		(fp_line
			(start -0.2794 0.9906)
			(end 0.2794 0.9906)
			(stroke
				(width 0.1)
				(type default)
			)
			(layer "F.Fab")
		)
		(fp_line
			(start -0.2794 -0.1016)
			(end -0.2794 0.9906)
			(stroke
				(width 0.1)
				(type default)
			)
			(layer "F.Fab")
		)
		(pad "1" smd rect
			(at 0 0 180)
			(size 0.508 0.508)
			(layers "F.Cu" "F.Mask" "F.Paste")
			(net "RMII_SPRNGVLLE_BMC_PCH_RXD1")
		)
		(pad "2" smd rect
			(at 0 0.889 180)
			(size 0.508 0.508)
			(layers "F.Cu" "F.Mask" "F.Paste")
			(net "RMII_SPRNGVLLE_BMC_PCH_RXD1_R1")
		)
		(zone
			(layer "F.Cu")
			(hatch none 0.5)
			(connect_pads
				(clearance 0)
			)
			(min_thickness 0.25)
			(keepout
				(tracks not_allowed)
				(vias allowed)
				(pads allowed)
				(copperpour not_allowed)
				(footprints allowed)
			)
			(placement
				(enabled no)
				(sheetname "")
			)
			(fill
				(thermal_gap 0.5)
				(thermal_bridge_width 0.5)
				(island_removal_mode 0)
			)
			(polygon
				(pts
					(xy 390.906 -87.9475) (xy 390.398 -87.9475) (xy 390.398 -87.5665) (xy 390.906 -87.5665)
				)
			)
		)
		(zone
			(layer "F.Cu")
			(hatch none 0.5)
			(connect_pads
				(clearance 0)
			)
			(min_thickness 0.25)
			(keepout
				(tracks allowed)
				(vias not_allowed)
				(pads allowed)
				(copperpour not_allowed)
				(footprints allowed)
			)
			(placement
				(enabled no)
				(sheetname "")
			)
			(fill
				(thermal_gap 0.5)
				(thermal_bridge_width 0.5)
				(island_removal_mode 0)
			)
			(polygon
				(pts
					(xy 390.906 -87.5665) (xy 390.398 -87.5665) (xy 390.398 -87.9475) (xy 390.906 -87.9475)
				)
			)
		)
	)
)
